(kicad_pcb
	(version 20211014)
	(generator pcbnew)
	(general
    (thickness 1.6)
  )
	(paper "A4")
	(title_block
    (title "SA800U (Snapdragon 845) Baseboard")
    (date "2023-10-19")
    (rev "1.0.3")
    (company "Antmicro Ltd.")
    (comment 1 "www.antmicro.com")
		(comment 9 "footprints 550-564 of 589")
	)
	(layers
    (0 "F.Cu" signal)
    (1 "In1.Cu" power)
    (2 "In2.Cu" signal)
    (3 "In3.Cu" signal)
    (4 "In4.Cu" power)
    (31 "B.Cu" signal)
    (32 "B.Adhes" user "B.Adhesive")
    (33 "F.Adhes" user "F.Adhesive")
    (34 "B.Paste" user)
    (35 "F.Paste" user)
    (36 "B.SilkS" user "B.Silkscreen")
    (37 "F.SilkS" user "F.Silkscreen")
    (38 "B.Mask" user)
    (39 "F.Mask" user)
    (40 "Dwgs.User" user "User.Drawings")
    (41 "Cmts.User" user "User.Comments")
    (42 "Eco1.User" user "User.Eco1")
    (43 "Eco2.User" user "User.Eco2")
    (44 "Edge.Cuts" user)
    (45 "Margin" user)
    (46 "B.CrtYd" user "B.Courtyard")
    (47 "F.CrtYd" user "F.Courtyard")
    (48 "B.Fab" user)
    (49 "F.Fab" user)
  )
	(footprint "sa800u-baseboard-hw-footprints:TP_SMD_0.75mm" (layer "B.Cu")
    (tedit 5E4A9375)
    (at 78.2 127.15)
    (property "Author" "Antmicro")
    (property "License" "Apache-2.0")
    (property "MPN" "")
    (property "Manufacturer" "")
    (property "Sheetfile" "psu.kicad_sch")
    (property "Sheetname" "PSU")
    (attr smd)
    (fp_text reference "TP57" (at 0.59 1.2 180) (layer "B.SilkS")
      (effects (font (size 0.7 0.7) (thickness 0.15)) (justify left bottom mirror))
    )
    (fp_text value "TP_0.75mm_SMD" (at 0 -1.2 180) (layer "B.Fab")
      (effects (font (size 0.7 0.7) (thickness 0.15)) (justify left bottom mirror))
    )
    (fp_text user "License: Apache-2.0" (at -0.4 -5.101 180) (layer "B.Fab") hide
      (effects (font (size 0.7 0.7) (thickness 0.15)) (justify left bottom mirror))
    )
    (fp_text user "${REFERENCE}" (at -0.4 -2.7 180) (layer "B.Fab") hide
      (effects (font (size 0.7 0.7) (thickness 0.15)) (justify left bottom mirror))
    )
    (fp_text user "Author: Antmicro" (at -0.4 -3.901 180) (layer "B.Fab") hide
      (effects (font (size 0.7 0.7) (thickness 0.15)) (justify left bottom mirror))
    )
    (pad "1" smd circle (at 0 0) (size 0.75 0.75) (layers "B.Cu" "B.Mask")
      (net 339 "/PSU/AUX_VALID") (pinfunction "1") (pintype "passive"))
  )
	(footprint "sa800u-baseboard-hw-footprints:TP_SMD_0.75mm" (layer "B.Cu")
    (tedit 5E4A9375)
    (at 71.2 128.8)
    (property "Author" "Antmicro")
    (property "License" "Apache-2.0")
    (property "MPN" "")
    (property "Manufacturer" "")
    (property "Sheetfile" "psu.kicad_sch")
    (property "Sheetname" "PSU")
    (attr smd)
    (fp_text reference "TP58" (at -0.38 0.78 180) (layer "B.SilkS")
      (effects (font (size 0.7 0.7) (thickness 0.15)) (justify left bottom mirror))
    )
    (fp_text value "TP_0.75mm_SMD" (at 0 -1.2 180) (layer "B.Fab")
      (effects (font (size 0.7 0.7) (thickness 0.15)) (justify left bottom mirror))
    )
    (fp_text user "License: Apache-2.0" (at -0.4 -5.101 180) (layer "B.Fab") hide
      (effects (font (size 0.7 0.7) (thickness 0.15)) (justify left bottom mirror))
    )
    (fp_text user "${REFERENCE}" (at -0.4 -2.7 180) (layer "B.Fab") hide
      (effects (font (size 0.7 0.7) (thickness 0.15)) (justify left bottom mirror))
    )
    (fp_text user "Author: Antmicro" (at -0.4 -3.901 180) (layer "B.Fab") hide
      (effects (font (size 0.7 0.7) (thickness 0.15)) (justify left bottom mirror))
    )
    (pad "1" smd circle (at 0 0) (size 0.75 0.75) (layers "B.Cu" "B.Mask")
      (net 1 "GND") (pinfunction "1") (pintype "passive"))
  )
	(footprint "sa800u-baseboard-hw-footprints:TP_SMD_0.75mm" (layer "B.Cu")
    (tedit 5E4A9375)
    (at 78.5 112)
    (property "Author" "Antmicro")
    (property "License" "Apache-2.0")
    (property "MPN" "")
    (property "Manufacturer" "")
    (property "Sheetfile" "psu.kicad_sch")
    (property "Sheetname" "PSU")
    (attr smd)
    (fp_text reference "TP62" (at 1.23 -0.45 180) (layer "B.SilkS")
      (effects (font (size 0.7 0.7) (thickness 0.15)) (justify left bottom mirror))
    )
    (fp_text value "TP_0.75mm_SMD" (at 0 -1.2 180) (layer "B.Fab")
      (effects (font (size 0.7 0.7) (thickness 0.15)) (justify left bottom mirror))
    )
    (fp_text user "Author: Antmicro" (at -0.4 -3.901 180) (layer "B.Fab") hide
      (effects (font (size 0.7 0.7) (thickness 0.15)) (justify left bottom mirror))
    )
    (fp_text user "${REFERENCE}" (at -0.4 -2.7 180) (layer "B.Fab") hide
      (effects (font (size 0.7 0.7) (thickness 0.15)) (justify left bottom mirror))
    )
    (fp_text user "License: Apache-2.0" (at -0.4 -5.101 180) (layer "B.Fab") hide
      (effects (font (size 0.7 0.7) (thickness 0.15)) (justify left bottom mirror))
    )
    (pad "1" smd circle (at 0 0) (size 0.75 0.75) (layers "B.Cu" "B.Mask")
      (net 74 "VDD") (pinfunction "1") (pintype "passive"))
  )
	(footprint "sa800u-baseboard-hw-footprints:TP_SMD_0.75mm" (layer "B.Cu")
    (tedit 5E4A9375)
    (at 123.4 128.2)
    (property "Author" "Antmicro")
    (property "License" "Apache-2.0")
    (property "MPN" "")
    (property "Manufacturer" "")
    (property "Sheetfile" "psu.kicad_sch")
    (property "Sheetname" "PSU")
    (attr smd)
    (fp_text reference "TP63" (at 1.2 -0.38 180) (layer "B.SilkS")
      (effects (font (size 0.7 0.7) (thickness 0.15)) (justify left bottom mirror))
    )
    (fp_text value "TP_0.75mm_SMD" (at 0 -1.2 180) (layer "B.Fab")
      (effects (font (size 0.7 0.7) (thickness 0.15)) (justify left bottom mirror))
    )
    (fp_text user "${REFERENCE}" (at -0.4 -2.7 180) (layer "B.Fab") hide
      (effects (font (size 0.7 0.7) (thickness 0.15)) (justify left bottom mirror))
    )
    (fp_text user "License: Apache-2.0" (at -0.4 -5.101 180) (layer "B.Fab") hide
      (effects (font (size 0.7 0.7) (thickness 0.15)) (justify left bottom mirror))
    )
    (fp_text user "Author: Antmicro" (at -0.4 -3.901 180) (layer "B.Fab") hide
      (effects (font (size 0.7 0.7) (thickness 0.15)) (justify left bottom mirror))
    )
    (pad "1" smd circle (at 0 0) (size 0.75 0.75) (layers "B.Cu" "B.Mask")
      (net 133 "5V_SYS") (pinfunction "1") (pintype "passive"))
  )
	(footprint "sa800u-baseboard-hw-footprints:TP_SMD_0.75mm" (layer "B.Cu")
    (tedit 5E4A9375)
    (at 81 112)
    (property "Author" "Antmicro")
    (property "License" "Apache-2.0")
    (property "MPN" "")
    (property "Manufacturer" "")
    (property "Sheetfile" "psu.kicad_sch")
    (property "Sheetname" "PSU")
    (attr smd)
    (fp_text reference "TP71" (at 1.63 -0.47 180) (layer "B.SilkS")
      (effects (font (size 0.7 0.7) (thickness 0.15)) (justify left bottom mirror))
    )
    (fp_text value "TP_0.75mm_SMD" (at 0 -1.2 180) (layer "B.Fab")
      (effects (font (size 0.7 0.7) (thickness 0.15)) (justify left bottom mirror))
    )
    (fp_text user "License: Apache-2.0" (at -0.4 -5.101 180) (layer "B.Fab") hide
      (effects (font (size 0.7 0.7) (thickness 0.15)) (justify left bottom mirror))
    )
    (fp_text user "Author: Antmicro" (at -0.4 -3.901 180) (layer "B.Fab") hide
      (effects (font (size 0.7 0.7) (thickness 0.15)) (justify left bottom mirror))
    )
    (fp_text user "${REFERENCE}" (at -0.4 -2.7 180) (layer "B.Fab") hide
      (effects (font (size 0.7 0.7) (thickness 0.15)) (justify left bottom mirror))
    )
    (pad "1" smd circle (at 0 0) (size 0.75 0.75) (layers "B.Cu" "B.Mask")
      (net 131 "3V3_SYS") (pinfunction "1") (pintype "passive"))
  )
	(footprint "sa800u-baseboard-hw-footprints:TP_SMD_0.75mm" (layer "B.Cu")
    (tedit 5E4A9375)
    (at 126 128.2)
    (property "Author" "Antmicro")
    (property "License" "Apache-2.0")
    (property "MPN" "")
    (property "Manufacturer" "")
    (property "Sheetfile" "psu.kicad_sch")
    (property "Sheetname" "PSU")
    (attr smd)
    (fp_text reference "TP72" (at 1.28 1.22 180) (layer "B.SilkS")
      (effects (font (size 0.7 0.7) (thickness 0.15)) (justify left bottom mirror))
    )
    (fp_text value "TP_0.75mm_SMD" (at 0 -1.2 180) (layer "B.Fab")
      (effects (font (size 0.7 0.7) (thickness 0.15)) (justify left bottom mirror))
    )
    (fp_text user "Author: Antmicro" (at -0.4 -3.901 180) (layer "B.Fab") hide
      (effects (font (size 0.7 0.7) (thickness 0.15)) (justify left bottom mirror))
    )
    (fp_text user "License: Apache-2.0" (at -0.4 -5.101 180) (layer "B.Fab") hide
      (effects (font (size 0.7 0.7) (thickness 0.15)) (justify left bottom mirror))
    )
    (fp_text user "${REFERENCE}" (at -0.4 -2.7 180) (layer "B.Fab") hide
      (effects (font (size 0.7 0.7) (thickness 0.15)) (justify left bottom mirror))
    )
    (pad "1" smd circle (at 0 0) (size 0.75 0.75) (layers "B.Cu" "B.Mask")
      (net 138 "1V2_SYS") (pinfunction "1") (pintype "passive"))
  )
	(footprint "sa800u-baseboard-hw-footprints:TP_SMD_0.75mm" (layer "B.Cu")
    (tedit 5E4A9375)
    (at 120.8 128.2)
    (property "Author" "Antmicro")
    (property "License" "Apache-2.0")
    (property "MPN" "")
    (property "Manufacturer" "")
    (property "Sheetfile" "psu.kicad_sch")
    (property "Sheetname" "PSU")
    (attr smd)
    (fp_text reference "TP76" (at 1.23 1.28 180) (layer "B.SilkS")
      (effects (font (size 0.7 0.7) (thickness 0.15)) (justify left bottom mirror))
    )
    (fp_text value "TP_0.75mm_SMD" (at 0 -1.2 180) (layer "B.Fab")
      (effects (font (size 0.7 0.7) (thickness 0.15)) (justify left bottom mirror))
    )
    (fp_text user "${REFERENCE}" (at -0.4 -2.7 180) (layer "B.Fab") hide
      (effects (font (size 0.7 0.7) (thickness 0.15)) (justify left bottom mirror))
    )
    (fp_text user "License: Apache-2.0" (at -0.4 -5.101 180) (layer "B.Fab") hide
      (effects (font (size 0.7 0.7) (thickness 0.15)) (justify left bottom mirror))
    )
    (fp_text user "Author: Antmicro" (at -0.4 -3.901 180) (layer "B.Fab") hide
      (effects (font (size 0.7 0.7) (thickness 0.15)) (justify left bottom mirror))
    )
    (pad "1" smd circle (at 0 0) (size 0.75 0.75) (layers "B.Cu" "B.Mask")
      (net 1 "GND") (pinfunction "1") (pintype "passive"))
  )
	(footprint "sa800u-baseboard-hw-footprints:TP_SMD_0.75mm" (layer "B.Cu")
    (tedit 5E4A9375)
    (at 85.2 119.2)
    (property "Author" "Antmicro")
    (property "License" "Apache-2.0")
    (property "MPN" "")
    (property "Manufacturer" "")
    (property "Sheetfile" "psu.kicad_sch")
    (property "Sheetname" "PSU")
    (attr smd)
    (fp_text reference "TP77" (at 1.26 1.24 180) (layer "B.SilkS")
      (effects (font (size 0.7 0.7) (thickness 0.15)) (justify left bottom mirror))
    )
    (fp_text value "TP_0.75mm_SMD" (at 0 -1.2 180) (layer "B.Fab")
      (effects (font (size 0.7 0.7) (thickness 0.15)) (justify left bottom mirror))
    )
    (fp_text user "License: Apache-2.0" (at -0.4 -5.101 180) (layer "B.Fab") hide
      (effects (font (size 0.7 0.7) (thickness 0.15)) (justify left bottom mirror))
    )
    (fp_text user "${REFERENCE}" (at -0.4 -2.7 180) (layer "B.Fab") hide
      (effects (font (size 0.7 0.7) (thickness 0.15)) (justify left bottom mirror))
    )
    (fp_text user "Author: Antmicro" (at -0.4 -3.901 180) (layer "B.Fab") hide
      (effects (font (size 0.7 0.7) (thickness 0.15)) (justify left bottom mirror))
    )
    (pad "1" smd circle (at 0 0) (size 0.75 0.75) (layers "B.Cu" "B.Mask")
      (net 1 "GND") (pinfunction "1") (pintype "passive"))
  )
	(footprint "sa800u-baseboard-hw-footprints:TP_SMD_0.75mm" (layer "B.Cu")
    (tedit 5E4A9375)
    (at 76 112)
    (property "Author" "Antmicro")
    (property "License" "Apache-2.0")
    (property "MPN" "")
    (property "Manufacturer" "")
    (property "Sheetfile" "psu.kicad_sch")
    (property "Sheetname" "PSU")
    (attr smd)
    (fp_text reference "TP75" (at 0.88 -0.45 180) (layer "B.SilkS")
      (effects (font (size 0.7 0.7) (thickness 0.15)) (justify left bottom mirror))
    )
    (fp_text value "TP_0.75mm_SMD" (at 0 -1.2 180) (layer "B.Fab")
      (effects (font (size 0.7 0.7) (thickness 0.15)) (justify left bottom mirror))
    )
    (fp_text user "${REFERENCE}" (at -0.4 -2.7 180) (layer "B.Fab") hide
      (effects (font (size 0.7 0.7) (thickness 0.15)) (justify left bottom mirror))
    )
    (fp_text user "License: Apache-2.0" (at -0.4 -5.101 180) (layer "B.Fab") hide
      (effects (font (size 0.7 0.7) (thickness 0.15)) (justify left bottom mirror))
    )
    (fp_text user "Author: Antmicro" (at -0.4 -3.901 180) (layer "B.Fab") hide
      (effects (font (size 0.7 0.7) (thickness 0.15)) (justify left bottom mirror))
    )
    (pad "1" smd circle (at 0 0) (size 0.75 0.75) (layers "B.Cu" "B.Mask")
      (net 1 "GND") (pinfunction "1") (pintype "passive"))
  )
	(footprint "sa800u-baseboard-hw-footprints:TP_SMD_0.75mm" (layer "B.Cu")
    (tedit 5E4A9375)
    (at 89.4 140.2)
    (property "Author" "Antmicro")
    (property "License" "Apache-2.0")
    (property "MPN" "")
    (property "Manufacturer" "")
    (property "Sheetfile" "usb-pd.kicad_sch")
    (property "Sheetname" "USB-PD")
    (attr smd)
    (fp_text reference "TP86" (at 0.94 1.22 180) (layer "B.SilkS")
      (effects (font (size 0.7 0.7) (thickness 0.15)) (justify left bottom mirror))
    )
    (fp_text value "TP_0.75mm_SMD" (at 0 -1.2 180) (layer "B.Fab")
      (effects (font (size 0.7 0.7) (thickness 0.15)) (justify left bottom mirror))
    )
    (fp_text user "Author: Antmicro" (at -0.4 -3.901 180) (layer "B.Fab") hide
      (effects (font (size 0.7 0.7) (thickness 0.15)) (justify left bottom mirror))
    )
    (fp_text user "${REFERENCE}" (at -0.4 -2.7 180) (layer "B.Fab") hide
      (effects (font (size 0.7 0.7) (thickness 0.15)) (justify left bottom mirror))
    )
    (fp_text user "License: Apache-2.0" (at -0.4 -5.101 180) (layer "B.Fab") hide
      (effects (font (size 0.7 0.7) (thickness 0.15)) (justify left bottom mirror))
    )
    (pad "1" smd circle (at 0 0) (size 0.75 0.75) (layers "B.Cu" "B.Mask")
      (net 143 "/USB-PD/PD_CC1") (pinfunction "1") (pintype "passive"))
  )
	(footprint "sa800u-baseboard-hw-footprints:TP_SMD_0.75mm" (layer "B.Cu")
    (tedit 5E4A9375)
    (at 92 140.2)
    (property "Author" "Antmicro")
    (property "License" "Apache-2.0")
    (property "MPN" "")
    (property "Manufacturer" "")
    (property "Sheetfile" "usb-pd.kicad_sch")
    (property "Sheetname" "USB-PD")
    (attr smd)
    (fp_text reference "TP87" (at 1.46 1.21 180) (layer "B.SilkS")
      (effects (font (size 0.7 0.7) (thickness 0.15)) (justify left bottom mirror))
    )
    (fp_text value "TP_0.75mm_SMD" (at 0 -1.2 180) (layer "B.Fab")
      (effects (font (size 0.7 0.7) (thickness 0.15)) (justify left bottom mirror))
    )
    (fp_text user "Author: Antmicro" (at -0.4 -3.901 180) (layer "B.Fab") hide
      (effects (font (size 0.7 0.7) (thickness 0.15)) (justify left bottom mirror))
    )
    (fp_text user "${REFERENCE}" (at -0.4 -2.7 180) (layer "B.Fab") hide
      (effects (font (size 0.7 0.7) (thickness 0.15)) (justify left bottom mirror))
    )
    (fp_text user "License: Apache-2.0" (at -0.4 -5.101 180) (layer "B.Fab") hide
      (effects (font (size 0.7 0.7) (thickness 0.15)) (justify left bottom mirror))
    )
    (pad "1" smd circle (at 0 0) (size 0.75 0.75) (layers "B.Cu" "B.Mask")
      (net 144 "/USB-PD/PD_CC2") (pinfunction "1") (pintype "passive"))
  )
	(footprint "sa800u-baseboard-hw-footprints:TP_SMD_0.75mm" (layer "B.Cu")
    (tedit 5E4A9375)
    (at 90.6 135)
    (property "Author" "Antmicro")
    (property "License" "Apache-2.0")
    (property "MPN" "")
    (property "Manufacturer" "")
    (property "Sheetfile" "usb-pd.kicad_sch")
    (property "Sheetname" "USB-PD")
    (attr smd)
    (fp_text reference "TP88" (at 1.21 -0.41 180) (layer "B.SilkS")
      (effects (font (size 0.7 0.7) (thickness 0.15)) (justify left bottom mirror))
    )
    (fp_text value "TP_0.75mm_SMD" (at 0 -1.2 180) (layer "B.Fab")
      (effects (font (size 0.7 0.7) (thickness 0.15)) (justify left bottom mirror))
    )
    (fp_text user "Author: Antmicro" (at -0.4 -3.901 180) (layer "B.Fab") hide
      (effects (font (size 0.7 0.7) (thickness 0.15)) (justify left bottom mirror))
    )
    (fp_text user "${REFERENCE}" (at -0.4 -2.7 180) (layer "B.Fab") hide
      (effects (font (size 0.7 0.7) (thickness 0.15)) (justify left bottom mirror))
    )
    (fp_text user "License: Apache-2.0" (at -0.4 -5.101 180) (layer "B.Fab") hide
      (effects (font (size 0.7 0.7) (thickness 0.15)) (justify left bottom mirror))
    )
    (pad "1" smd circle (at 0 0) (size 0.75 0.75) (layers "B.Cu" "B.Mask")
      (net 351 "USB_PD_DISABLE") (pinfunction "1") (pintype "passive"))
  )
	(footprint "sa800u-baseboard-hw-footprints:TP_SMD_0.75mm" (layer "B.Cu")
    (tedit 5E4A9375)
    (at 89.6 137.8)
    (property "Author" "Antmicro")
    (property "License" "Apache-2.0")
    (property "MPN" "")
    (property "Manufacturer" "")
    (property "Sheetfile" "usb-pd.kicad_sch")
    (property "Sheetname" "USB-PD")
    (attr smd)
    (fp_text reference "TP90" (at 1.19 -0.49 180) (layer "B.SilkS")
      (effects (font (size 0.7 0.7) (thickness 0.15)) (justify left bottom mirror))
    )
    (fp_text value "TP_0.75mm_SMD" (at 0 -1.2 180) (layer "B.Fab")
      (effects (font (size 0.7 0.7) (thickness 0.15)) (justify left bottom mirror))
    )
    (fp_text user "License: Apache-2.0" (at -0.4 -5.101 180) (layer "B.Fab") hide
      (effects (font (size 0.7 0.7) (thickness 0.15)) (justify left bottom mirror))
    )
    (fp_text user "Author: Antmicro" (at -0.4 -3.901 180) (layer "B.Fab") hide
      (effects (font (size 0.7 0.7) (thickness 0.15)) (justify left bottom mirror))
    )
    (fp_text user "${REFERENCE}" (at -0.4 -2.7 180) (layer "B.Fab") hide
      (effects (font (size 0.7 0.7) (thickness 0.15)) (justify left bottom mirror))
    )
    (pad "1" smd circle (at 0 0) (size 0.75 0.75) (layers "B.Cu" "B.Mask")
      (net 141 "/USB-PD/VREG_2V7") (pinfunction "1") (pintype "passive"))
  )
	(footprint "sa800u-baseboard-hw-footprints:TP_SMD_0.75mm" (layer "B.Cu")
    (tedit 5E4A9375)
    (at 95.6 132.8)
    (property "Author" "Antmicro")
    (property "License" "Apache-2.0")
    (property "MPN" "")
    (property "Manufacturer" "")
    (property "Sheetfile" "usb-pd.kicad_sch")
    (property "Sheetname" "USB-PD")
    (attr smd)
    (fp_text reference "TP93" (at -0.4 0.37 180) (layer "B.SilkS")
      (effects (font (size 0.7 0.7) (thickness 0.15)) (justify left bottom mirror))
    )
    (fp_text value "TP_0.75mm_SMD" (at 0 -1.2 180) (layer "B.Fab")
      (effects (font (size 0.7 0.7) (thickness 0.15)) (justify left bottom mirror))
    )
    (fp_text user "Author: Antmicro" (at -0.4 -3.901 180) (layer "B.Fab") hide
      (effects (font (size 0.7 0.7) (thickness 0.15)) (justify left bottom mirror))
    )
    (fp_text user "License: Apache-2.0" (at -0.4 -5.101 180) (layer "B.Fab") hide
      (effects (font (size 0.7 0.7) (thickness 0.15)) (justify left bottom mirror))
    )
    (fp_text user "${REFERENCE}" (at -0.4 -2.7 180) (layer "B.Fab") hide
      (effects (font (size 0.7 0.7) (thickness 0.15)) (justify left bottom mirror))
    )
    (pad "1" smd circle (at 0 0) (size 0.75 0.75) (layers "B.Cu" "B.Mask")
      (net 169 "/USB-PD/STUSB4500_PWR_OK2") (pinfunction "1") (pintype "passive"))
  )
	(footprint "sa800u-baseboard-hw-footprints:TP_SMD_0.75mm" (layer "B.Cu")
    (tedit 5E4A9375)
    (at 95.6 131.2)
    (property "Author" "Antmicro")
    (property "License" "Apache-2.0")
    (property "MPN" "")
    (property "Manufacturer" "")
    (property "Sheetfile" "usb-pd.kicad_sch")
    (property "Sheetname" "USB-PD")
    (attr smd)
    (fp_text reference "TP94" (at -0.5 0.34 180) (layer "B.SilkS")
      (effects (font (size 0.7 0.7) (thickness 0.15)) (justify left bottom mirror))
    )
    (fp_text value "TP_0.75mm_SMD" (at 0 -1.2 180) (layer "B.Fab")
      (effects (font (size 0.7 0.7) (thickness 0.15)) (justify left bottom mirror))
    )
    (fp_text user "Author: Antmicro" (at -0.4 -3.901 180) (layer "B.Fab") hide
      (effects (font (size 0.7 0.7) (thickness 0.15)) (justify left bottom mirror))
    )
    (fp_text user "License: Apache-2.0" (at -0.4 -5.101 180) (layer "B.Fab") hide
      (effects (font (size 0.7 0.7) (thickness 0.15)) (justify left bottom mirror))
    )
    (fp_text user "${REFERENCE}" (at -0.4 -2.7 180) (layer "B.Fab") hide
      (effects (font (size 0.7 0.7) (thickness 0.15)) (justify left bottom mirror))
    )
    (pad "1" smd circle (at 0 0) (size 0.75 0.75) (layers "B.Cu" "B.Mask")
      (net 170 "/USB-PD/STUSB4500_PWR_OK3") (pinfunction "1") (pintype "passive"))
  )
)
